# T6G (Grand Teton) — schematic netlist excerpt (pin names and nets, part order shuffled) for the footprints in the layout excerpt that follows; sources: Cadence DE-HDL packaged netlist, KiCad conversion of 04192023_DAF0TMB3IC0_F0TG_MB_C_brd_V02_OCP.brd

R333  Q_RES  0 5% CHIP  pkg 0402LF  page 188 : A = FM_P5V_EN ; B = VR_P5V_EN
R9029  Q_RES  0 5% EMPTY  pkg 0402LF  page 136 : A = OCP_SFF_AUX_PWR_EN_R3 ; B = HP_LVC3_OCP_V3_1_PWRGD_R1

(kicad_pcb
	(version 20260206)
	(generator "pcbnew")
	(generator_version "10.0")
	(general
		(thickness 1.6)
		(legacy_teardrops no)
	)
	(paper "A4")
	(title_block
		(title "04192023_DAF0TMB3IC0_F0TG_MB_C_brd_V02_OCP.brd")
		(comment 1 "Grand Teton / footprints 3727-3728 of 8354")
	)
	(layers
		(0 "F.Cu" signal "TOP")
		(4 "In1.Cu" signal "GND")
		(6 "In2.Cu" signal "IN1")
		(8 "In3.Cu" signal "GND1")
		(10 "In4.Cu" signal "IN2")
		(12 "In5.Cu" signal "GND2")
		(14 "In6.Cu" signal "IN3")
		(16 "In7.Cu" signal "GND3")
		(18 "In8.Cu" signal "VCC")
		(20 "In9.Cu" signal "VCC1")
		(22 "In10.Cu" signal "GND4")
		(24 "In11.Cu" signal "IN4")
		(26 "In12.Cu" signal "GND5")
		(28 "In13.Cu" signal "IN5")
		(30 "In14.Cu" signal "GND6")
		(32 "In15.Cu" signal "IN6")
		(34 "In16.Cu" signal "GND7")
		(2 "B.Cu" signal "BOTTOM")
		(9 "F.Adhes" user "F.Adhesive")
		(11 "B.Adhes" user "B.Adhesive")
		(13 "F.Paste" user "Package Geometry/Pastemask Top")
		(15 "B.Paste" user "Package Geometry/Pastemask Bottom")
		(5 "F.SilkS" user "Ref Des/Silkscreen Top")
		(7 "B.SilkS" user "Ref Des/Silkscreen Bottom")
		(1 "F.Mask" user "Board Geometry/Soldermask Top")
		(3 "B.Mask" user "Board Geometry/Soldermask Bottom")
		(17 "Dwgs.User" user "User.Drawings")
		(19 "Cmts.User" user "User.Comments")
		(21 "Eco1.User" user "User.Eco1")
		(23 "Eco2.User" user "User.Eco2")
		(25 "Edge.Cuts" user "Board Geometry/Outline")
		(27 "Margin" user)
		(31 "F.CrtYd" user "Package Geometry/Place Bound Top")
		(29 "B.CrtYd" user "Package Geometry/Place Bound Bottom")
		(35 "F.Fab" user "Ref Des/Assembly Top")
		(33 "B.Fab" user "Ref Des/Assembly Bottom")
	)
	(footprint ""
		(layer "F.Cu")
		(at 148.494242 -108.699046 180)
		(property "Reference" "R333"
			(at 0 0 180)
			(layer "F.SilkS")
			(hide yes)
			(effects
				(font
					(size 1.27 1.27)
				)
			)
		)
		(property "Value" ""
			(at 0 0 180)
			(layer "F.Fab")
			(effects
				(font
					(size 1.27 1.27)
				)
			)
		)
		(duplicate_pad_numbers_are_jumpers no)
		(fp_line
			(start 0.7874 0.4064)
			(end -0.7874 0.4064)
			(stroke
				(width 0.1524)
				(type default)
			)
			(layer "F.SilkS")
		)
		(fp_line
			(start 0.7874 -0.4064)
			(end 0.7874 0.4064)
			(stroke
				(width 0.1524)
				(type default)
			)
			(layer "F.SilkS")
		)
		(fp_line
			(start -0.7874 0.4064)
			(end -0.7874 -0.4064)
			(stroke
				(width 0.1524)
				(type default)
			)
			(layer "F.SilkS")
		)
		(fp_line
			(start -0.7874 -0.4064)
			(end 0.7874 -0.4064)
			(stroke
				(width 0.1524)
				(type default)
			)
			(layer "F.SilkS")
		)
		(fp_line
			(start 0.67945 0.3048)
			(end 0.120396 0.3048)
			(stroke
				(width 0.1)
				(type default)
			)
			(layer "F.Fab")
		)
		(fp_line
			(start 0.67945 -0.3048)
			(end 0.67945 0.3048)
			(stroke
				(width 0.1)
				(type default)
			)
			(layer "F.Fab")
		)
		(fp_line
			(start 0.12065 -0.2794)
			(end 0.12065 -0.3048)
			(stroke
				(width 0.1)
				(type default)
			)
			(layer "F.Fab")
		)
		(fp_line
			(start 0.12065 -0.3048)
			(end 0.67945 -0.3048)
			(stroke
				(width 0.1)
				(type default)
			)
			(layer "F.Fab")
		)
		(fp_line
			(start 0.120396 0.3048)
			(end 0.120396 0.2794)
			(stroke
				(width 0.1)
				(type default)
			)
			(layer "F.Fab")
		)
		(fp_line
			(start 0.120396 0.2794)
			(end -0.12065 0.2794)
			(stroke
				(width 0.1)
				(type default)
			)
			(layer "F.Fab")
		)
		(fp_line
			(start -0.12065 0.3048)
			(end -0.67945 0.3048)
			(stroke
				(width 0.1)
				(type default)
			)
			(layer "F.Fab")
		)
		(fp_line
			(start -0.12065 0.2794)
			(end -0.12065 0.3048)
			(stroke
				(width 0.1)
				(type default)
			)
			(layer "F.Fab")
		)
		(fp_line
			(start -0.12065 -0.2794)
			(end 0.12065 -0.2794)
			(stroke
				(width 0.1)
				(type default)
			)
			(layer "F.Fab")
		)
		(fp_line
			(start -0.12065 -0.305054)
			(end -0.12065 -0.2794)
			(stroke
				(width 0.1)
				(type default)
			)
			(layer "F.Fab")
		)
		(fp_line
			(start -0.67945 0.3048)
			(end -0.67945 -0.305054)
			(stroke
				(width 0.1)
				(type default)
			)
			(layer "F.Fab")
		)
		(fp_line
			(start -0.67945 -0.305054)
			(end -0.12065 -0.305054)
			(stroke
				(width 0.1)
				(type default)
			)
			(layer "F.Fab")
		)
		(pad "1" smd circle
			(at -0.40005 0 180)
			(size 0 0)
			(layers "F.Cu" "F.Mask" "F.Paste")
			(net "FM_P5V_EN")
		)
		(pad "2" smd circle
			(at 0.40005 0 180)
			(size 0 0)
			(layers "F.Cu" "F.Mask" "F.Paste")
			(net "VR_P5V_EN")
		)
	)
	(footprint ""
		(layer "F.Cu")
		(at 217.861134 -97.54362)
		(property "Reference" "R9029"
			(at 0 0 0)
			(layer "F.SilkS")
			(hide yes)
			(effects
				(font
					(size 1.27 1.27)
				)
			)
		)
		(property "Value" ""
			(at 0 0 0)
			(layer "F.Fab")
			(effects
				(font
					(size 1.27 1.27)
				)
			)
		)
		(duplicate_pad_numbers_are_jumpers no)
		(fp_line
			(start -0.7874 -0.4064)
			(end 0.7874 -0.4064)
			(stroke
				(width 0.1524)
				(type default)
			)
			(layer "F.SilkS")
		)
		(fp_line
			(start -0.7874 0.4064)
			(end -0.7874 -0.4064)
			(stroke
				(width 0.1524)
				(type default)
			)
			(layer "F.SilkS")
		)
		(fp_line
			(start 0.7874 -0.4064)
			(end 0.7874 0.4064)
			(stroke
				(width 0.1524)
				(type default)
			)
			(layer "F.SilkS")
		)
		(fp_line
			(start 0.7874 0.4064)
			(end -0.7874 0.4064)
			(stroke
				(width 0.1524)
				(type default)
			)
			(layer "F.SilkS")
		)
		(fp_line
			(start -0.67945 -0.305054)
			(end -0.12065 -0.305054)
			(stroke
				(width 0.1)
				(type default)
			)
			(layer "F.Fab")
		)
		(fp_line
			(start -0.67945 0.3048)
			(end -0.67945 -0.305054)
			(stroke
				(width 0.1)
				(type default)
			)
			(layer "F.Fab")
		)
		(fp_line
			(start -0.12065 -0.305054)
			(end -0.12065 -0.2794)
			(stroke
				(width 0.1)
				(type default)
			)
			(layer "F.Fab")
		)
		(fp_line
			(start -0.12065 -0.2794)
			(end 0.12065 -0.2794)
			(stroke
				(width 0.1)
				(type default)
			)
			(layer "F.Fab")
		)
		(fp_line
			(start -0.12065 0.2794)
			(end -0.12065 0.3048)
			(stroke
				(width 0.1)
				(type default)
			)
			(layer "F.Fab")
		)
		(fp_line
			(start -0.12065 0.3048)
			(end -0.67945 0.3048)
			(stroke
				(width 0.1)
				(type default)
			)
			(layer "F.Fab")
		)
		(fp_line
			(start 0.120396 0.2794)
			(end -0.12065 0.2794)
			(stroke
				(width 0.1)
				(type default)
			)
			(layer "F.Fab")
		)
		(fp_line
			(start 0.120396 0.3048)
			(end 0.120396 0.2794)
			(stroke
				(width 0.1)
				(type default)
			)
			(layer "F.Fab")
		)
		(fp_line
			(start 0.12065 -0.3048)
			(end 0.67945 -0.3048)
			(stroke
				(width 0.1)
				(type default)
			)
			(layer "F.Fab")
		)
		(fp_line
			(start 0.12065 -0.2794)
			(end 0.12065 -0.3048)
			(stroke
				(width 0.1)
				(type default)
			)
			(layer "F.Fab")
		)
		(fp_line
			(start 0.67945 -0.3048)
			(end 0.67945 0.3048)
			(stroke
				(width 0.1)
				(type default)
			)
			(layer "F.Fab")
		)
		(fp_line
			(start 0.67945 0.3048)
			(end 0.120396 0.3048)
			(stroke
				(width 0.1)
				(type default)
			)
			(layer "F.Fab")
		)
		(pad "1" smd circle
			(at -0.40005 0)
			(size 0 0)
			(layers "F.Cu" "F.Mask" "F.Paste")
			(net "OCP_SFF_AUX_PWR_EN_R3")
		)
		(pad "2" smd circle
			(at 0.40005 0)
			(size 0 0)
			(layers "F.Cu" "F.Mask" "F.Paste")
			(net "HP_LVC3_OCP_V3_1_PWRGD_R1")
		)
	)
)
